FILE_TYPE = MULTI_PHYS_TABLE;

PART 'PCA9517ADP'

{========================================================================================}
:PACK_TYPE | VALUE        | MATERIAL | PART_NUMBER       = STANDARD | LIFECYCLE      | PART_NUMBER       | JEDEC_TYPE | CLASS | DESCRIPTION                              | HEIGHT   | COMPONENT_TYPE | LEAD_LENGTH | DFM_EXCLUSION | DAY        ;
{========================================================================================}
 'SMLF'    | 'PCA9517ADP' | 'IC'     | 'AL009517K00'(!)  = ''       | ''             | 'AL009517K00'     |'TSSOP8_3'| 'IC'  | 'IC OTHER (8P) PCA9517ADP(TSSOP8)'       | '.044IN' | 'SMALLSMT'     | ''          | ''            | '20101012'
 'SMLF'    | 'PCA9517ADP' | 'EMPTY'  | 'AL009517K00'(!)  = ''       | ''             | 'AL009517K00'     |'TSSOP8_3'| 'IO'  | 'IC OTHER (8P) PCA9517ADP(TSSOP8)'       | '.044IN' | 'SMALLSMT'     | ''          | ''            | '20101012'
 'SMLF'    | 'PCA9517ADP' | 'IC'     | 'AL009517K00SEL1'(!) = ''       | ''               | 'AL009517K00SEL1' |'TSSOP8_3'| 'IC'  | 'IC OTHER (8P) PCA9517ADP(TSSOP8)SELASN' | ''       | ''             | ''          | ''            | '20230719'
 'SMLF'    | 'PCA9517ADP' | 'EMPTY'  | 'AL009517K00SEL1'(!) = ''       | ''               | 'AL009517K00SEL1' |'TSSOP8_3'| 'IC'  | 'IC OTHER (8P) PCA9517ADP(TSSOP8)SELASN' | ''       | ''             | ''          | ''            | '20230719'

END_PART

END.

